(kicad_pcb
	(version 20260206)
	(generator "pcbnew")
	(generator_version "10.0")
	(general
		(thickness 1.6)
		(legacy_teardrops no)
	)
	(paper "A4")
	(title_block
		(title "Bryce Canyon_SCC_16316-1_OCP.brd")
		(comment 1 "Bryce Canyon / footprint 482 of 1561 (U2), pads 603-726 of 896")
	)
	(layers
		(0 "F.Cu" signal "TOP")
		(4 "In1.Cu" signal "L2GND")
		(6 "In2.Cu" signal "L3")
		(8 "In3.Cu" signal "L4VCC")
		(10 "In4.Cu" signal "L5VCC")
		(12 "In5.Cu" signal "L6")
		(14 "In6.Cu" signal "L7GND")
		(2 "B.Cu" signal "BOTTOM")
		(9 "F.Adhes" user "F.Adhesive")
		(11 "B.Adhes" user "B.Adhesive")
		(13 "F.Paste" user "Package Geometry/Pastemask Top")
		(15 "B.Paste" user "Package Geometry/Pastemask Bottom")
		(5 "F.SilkS" user "Ref Des/Silkscreen Top")
		(7 "B.SilkS" user "Ref Des/Silkscreen Bottom")
		(1 "F.Mask" user "Board Geometry/Soldermask Top")
		(3 "B.Mask" user "Board Geometry/Soldermask Bottom")
		(17 "Dwgs.User" user "User.Drawings")
		(19 "Cmts.User" user "User.Comments")
		(21 "Eco1.User" user "User.Eco1")
		(23 "Eco2.User" user "User.Eco2")
		(25 "Edge.Cuts" user "Board Geometry/Outline")
		(27 "Margin" user)
		(31 "F.CrtYd" user "Package Geometry/Place Bound Top")
		(29 "B.CrtYd" user "Package Geometry/Place Bound Bottom")
		(35 "F.Fab" user "Ref Des/Assembly Top")
		(33 "B.Fab" user "Ref Des/Assembly Bottom")
	)
	(footprint ""
		(layer "F.Cu")
		(at 174.999904 -39.99992)
		(property "Reference" "U2"
			(at 0 0 0)
			(layer "F.SilkS")
			(hide yes)
			(effects
				(font
					(size 1.27 1.27)
				)
			)
		)
		(property "Value" "SAS3008C0-1-DB-500020657-1-GP"
			(at -20.374102 -5.0292 0)
			(unlocked yes)
			(layer "F.Fab")
			(hide yes)
			(effects
				(font
					(size 1.016 1.016)
					(thickness 0.1524)
				)
			)
		)
		(property "Device Type" "BGA896D25H78"
			(at -20.374102 -6.5532 0)
			(unlocked yes)
			(layer "F.Fab")
			(hide yes)
			(effects
				(font
					(size 1.016 1.016)
					(thickness 0.1524)
				)
			)
		)
		(duplicate_pad_numbers_are_jumpers no)
		(pad "L7" smd circle
			(at -6.800088 -3.599942)
			(size 0.3556 0.3556)
			(layers "F.Cu" "F.Mask" "F.Paste")
			(net "GND")
		)
		(pad "L8" smd circle
			(at -5.999988 -3.599942)
			(size 0.3556 0.3556)
			(layers "F.Cu" "F.Mask" "F.Paste")
			(net "GND")
		)
		(pad "L9" smd circle
			(at -5.199888 -3.599942)
			(size 0.3556 0.3556)
			(layers "F.Cu" "F.Mask" "F.Paste")
			(net "GND")
		)
		(pad "L10" smd circle
			(at -4.400042 -3.599942)
			(size 0.3556 0.3556)
			(layers "F.Cu" "F.Mask" "F.Paste")
			(net "GND")
		)
		(pad "L11" smd circle
			(at -3.599942 -3.599942)
			(size 0.3556 0.3556)
			(layers "F.Cu" "F.Mask" "F.Paste")
			(net "GND")
		)
		(pad "L12" smd circle
			(at -2.800096 -3.599942)
			(size 0.3556 0.3556)
			(layers "F.Cu" "F.Mask" "F.Paste")
			(net "GND")
		)
		(pad "L13" smd circle
			(at -1.999996 -3.599942)
			(size 0.3556 0.3556)
			(layers "F.Cu" "F.Mask" "F.Paste")
			(net "GND")
		)
		(pad "L14" smd circle
			(at -1.199896 -3.599942)
			(size 0.3556 0.3556)
			(layers "F.Cu" "F.Mask" "F.Paste")
			(net "P0V975")
		)
		(pad "L15" smd circle
			(at -0.40005 -3.599942)
			(size 0.3556 0.3556)
			(layers "F.Cu" "F.Mask" "F.Paste")
			(net "GND")
		)
		(pad "L16" smd circle
			(at 0.40005 -3.599942)
			(size 0.3556 0.3556)
			(layers "F.Cu" "F.Mask" "F.Paste")
			(net "P0V975")
		)
		(pad "L17" smd circle
			(at 1.199896 -3.599942)
			(size 0.3556 0.3556)
			(layers "F.Cu" "F.Mask" "F.Paste")
			(net "GND")
		)
		(pad "L18" smd circle
			(at 1.999996 -3.599942)
			(size 0.3556 0.3556)
			(layers "F.Cu" "F.Mask" "F.Paste")
			(net "P0V975")
		)
		(pad "L19" smd circle
			(at 2.800096 -3.599942)
			(size 0.3556 0.3556)
			(layers "F.Cu" "F.Mask" "F.Paste")
			(net "GND")
		)
		(pad "L20" smd circle
			(at 3.599942 -3.599942)
			(size 0.3556 0.3556)
			(layers "F.Cu" "F.Mask" "F.Paste")
			(net "P0V975")
		)
		(pad "L21" smd circle
			(at 4.400042 -3.599942)
			(size 0.3556 0.3556)
			(layers "F.Cu" "F.Mask" "F.Paste")
			(net "GND")
		)
		(pad "L22" smd circle
			(at 5.199888 -3.599942)
			(size 0.3556 0.3556)
			(layers "F.Cu" "F.Mask" "F.Paste")
			(net "VDDIO_15")
		)
		(pad "L23" smd circle
			(at 5.999988 -3.599942)
			(size 0.3556 0.3556)
			(layers "F.Cu" "F.Mask" "F.Paste")
			(net "GND")
		)
		(pad "L24" smd circle
			(at 6.800088 -3.599942)
			(size 0.3556 0.3556)
			(layers "F.Cu" "F.Mask" "F.Paste")
			(net "GND")
		)
		(pad "L25" smd circle
			(at 7.599934 -3.599942)
			(size 0.3556 0.3556)
			(layers "F.Cu" "F.Mask" "F.Paste")
			(net "GND")
		)
		(pad "L26" smd circle
			(at 8.400034 -3.599942)
			(size 0.3556 0.3556)
			(layers "F.Cu" "F.Mask" "F.Paste")
			(net "GND")
		)
		(pad "L27" smd circle
			(at 9.19988 -3.599942)
			(size 0.3556 0.3556)
			(layers "F.Cu" "F.Mask" "F.Paste")
			(net "P1V8_C")
		)
		(pad "L28" smd circle
			(at 9.99998 -3.599942)
			(size 0.3556 0.3556)
			(layers "F.Cu" "F.Mask" "F.Paste")
			(net "GND")
		)
		(pad "L29" smd circle
			(at 10.80008 -3.599942)
			(size 0.3556 0.3556)
			(layers "F.Cu" "F.Mask" "F.Paste")
			(net "XM_DATA_4")
		)
		(pad "L30" smd circle
			(at 11.599926 -3.599942)
			(size 0.3556 0.3556)
			(layers "F.Cu" "F.Mask" "F.Paste")
			(net "XM_DATA_3")
		)
		(pad "M1" smd circle
			(at -11.599926 -2.800096)
			(size 0.3556 0.3556)
			(layers "F.Cu" "F.Mask" "F.Paste")
			(net "SIO_CLK_0")
		)
		(pad "M2" smd circle
			(at -10.80008 -2.800096)
			(size 0.3556 0.3556)
			(layers "F.Cu" "F.Mask" "F.Paste")
			(net "SIO_DOUT_1")
		)
		(pad "M3" smd circle
			(at -9.99998 -2.800096)
			(size 0.3556 0.3556)
			(layers "F.Cu" "F.Mask" "F.Paste")
			(net "SIO_LOAD_0")
		)
		(pad "M4" smd circle
			(at -9.19988 -2.800096)
			(size 0.3556 0.3556)
			(layers "F.Cu" "F.Mask" "F.Paste")
			(net "P1V8_C")
		)
		(pad "M5" smd circle
			(at -8.400034 -2.800096)
			(size 0.3556 0.3556)
			(layers "F.Cu" "F.Mask" "F.Paste")
			(net "GND")
		)
		(pad "M6" smd circle
			(at -7.599934 -2.800096)
			(size 0.3556 0.3556)
			(layers "F.Cu" "F.Mask" "F.Paste")
			(net "ICE_SEL")
		)
		(pad "M7" smd circle
			(at -6.800088 -2.800096)
			(size 0.3556 0.3556)
			(layers "F.Cu" "F.Mask" "F.Paste")
			(net "GND")
		)
		(pad "M8" smd circle
			(at -5.999988 -2.800096)
			(size 0.3556 0.3556)
			(layers "F.Cu" "F.Mask" "F.Paste")
			(net "GND")
		)
		(pad "M9" smd circle
			(at -5.199888 -2.800096)
			(size 0.3556 0.3556)
			(layers "F.Cu" "F.Mask" "F.Paste")
			(net "P1V8_C")
		)
		(pad "M10" smd circle
			(at -4.400042 -2.800096)
			(size 0.3556 0.3556)
			(layers "F.Cu" "F.Mask" "F.Paste")
			(net "GND")
		)
		(pad "M11" smd circle
			(at -3.599942 -2.800096)
			(size 0.3556 0.3556)
			(layers "F.Cu" "F.Mask" "F.Paste")
			(net "P0V975")
		)
		(pad "M12" smd circle
			(at -2.800096 -2.800096)
			(size 0.3556 0.3556)
			(layers "F.Cu" "F.Mask" "F.Paste")
			(net "GND")
		)
		(pad "M13" smd circle
			(at -1.999996 -2.800096)
			(size 0.3556 0.3556)
			(layers "F.Cu" "F.Mask" "F.Paste")
			(net "P0V975")
		)
		(pad "M14" smd circle
			(at -1.199896 -2.800096)
			(size 0.3556 0.3556)
			(layers "F.Cu" "F.Mask" "F.Paste")
			(net "GND")
		)
		(pad "M15" smd circle
			(at -0.40005 -2.800096)
			(size 0.3556 0.3556)
			(layers "F.Cu" "F.Mask" "F.Paste")
			(net "P0V975")
		)
		(pad "M16" smd circle
			(at 0.40005 -2.800096)
			(size 0.3556 0.3556)
			(layers "F.Cu" "F.Mask" "F.Paste")
			(net "GND")
		)
		(pad "M17" smd circle
			(at 1.199896 -2.800096)
			(size 0.3556 0.3556)
			(layers "F.Cu" "F.Mask" "F.Paste")
			(net "P0V975")
		)
		(pad "M18" smd circle
			(at 1.999996 -2.800096)
			(size 0.3556 0.3556)
			(layers "F.Cu" "F.Mask" "F.Paste")
			(net "GND")
		)
		(pad "M19" smd circle
			(at 2.800096 -2.800096)
			(size 0.3556 0.3556)
			(layers "F.Cu" "F.Mask" "F.Paste")
			(net "P0V975")
		)
		(pad "M20" smd circle
			(at 3.599942 -2.800096)
			(size 0.3556 0.3556)
			(layers "F.Cu" "F.Mask" "F.Paste")
			(net "GND")
		)
		(pad "M21" smd circle
			(at 4.400042 -2.800096)
			(size 0.3556 0.3556)
			(layers "F.Cu" "F.Mask" "F.Paste")
			(net "P0V975")
		)
		(pad "M22" smd circle
			(at 5.199888 -2.800096)
			(size 0.3556 0.3556)
			(layers "F.Cu" "F.Mask" "F.Paste")
			(net "GND")
		)
		(pad "M23" smd circle
			(at 5.999988 -2.800096)
			(size 0.3556 0.3556)
			(layers "F.Cu" "F.Mask" "F.Paste")
			(net "GND")
		)
		(pad "M24" smd circle
			(at 6.800088 -2.800096)
			(size 0.3556 0.3556)
			(layers "F.Cu" "F.Mask" "F.Paste")
			(net "GND")
		)
		(pad "M25" smd circle
			(at 7.599934 -2.800096)
			(size 0.3556 0.3556)
			(layers "F.Cu" "F.Mask" "F.Paste")
			(net "GND")
		)
		(pad "M26" smd circle
			(at 8.400034 -2.800096)
			(size 0.3556 0.3556)
			(layers "F.Cu" "F.Mask" "F.Paste")
			(net "GND")
		)
		(pad "M27" smd circle
			(at 9.19988 -2.800096)
			(size 0.3556 0.3556)
			(layers "F.Cu" "F.Mask" "F.Paste")
			(net "GND")
		)
		(pad "M28" smd circle
			(at 9.99998 -2.800096)
			(size 0.3556 0.3556)
			(layers "F.Cu" "F.Mask" "F.Paste")
			(net "GND")
		)
		(pad "M29" smd circle
			(at 10.80008 -2.800096)
			(size 0.3556 0.3556)
			(layers "F.Cu" "F.Mask" "F.Paste")
			(net "GND")
		)
		(pad "M30" smd circle
			(at 11.599926 -2.800096)
			(size 0.3556 0.3556)
			(layers "F.Cu" "F.Mask" "F.Paste")
			(net "GND")
		)
		(pad "N1" smd circle
			(at -11.599926 -1.999996)
			(size 0.3556 0.3556)
			(layers "F.Cu" "F.Mask" "F.Paste")
			(net "GND")
		)
		(pad "N2" smd circle
			(at -10.80008 -1.999996)
			(size 0.3556 0.3556)
			(layers "F.Cu" "F.Mask" "F.Paste")
			(net "GND")
		)
		(pad "N3" smd circle
			(at -9.99998 -1.999996)
			(size 0.3556 0.3556)
			(layers "F.Cu" "F.Mask" "F.Paste")
			(net "P1V8_C")
		)
		(pad "N4" smd circle
			(at -9.19988 -1.999996)
			(size 0.3556 0.3556)
			(layers "F.Cu" "F.Mask" "F.Paste")
			(net "GND")
		)
		(pad "N5" smd circle
			(at -8.400034 -1.999996)
			(size 0.3556 0.3556)
			(layers "F.Cu" "F.Mask" "F.Paste")
			(net "Net_1192")
		)
		(pad "N6" smd circle
			(at -7.599934 -1.999996)
			(size 0.3556 0.3556)
			(layers "F.Cu" "F.Mask" "F.Paste")
			(net "Net_1193")
		)
		(pad "N7" smd circle
			(at -6.800088 -1.999996)
			(size 0.3556 0.3556)
			(layers "F.Cu" "F.Mask" "F.Paste")
			(net "GND")
		)
		(pad "N8" smd circle
			(at -5.999988 -1.999996)
			(size 0.3556 0.3556)
			(layers "F.Cu" "F.Mask" "F.Paste")
			(net "GND")
		)
		(pad "N9" smd circle
			(at -5.199888 -1.999996)
			(size 0.3556 0.3556)
			(layers "F.Cu" "F.Mask" "F.Paste")
			(net "GND")
		)
		(pad "N10" smd circle
			(at -4.400042 -1.999996)
			(size 0.3556 0.3556)
			(layers "F.Cu" "F.Mask" "F.Paste")
			(net "GND")
		)
		(pad "N11" smd circle
			(at -3.599942 -1.999996)
			(size 0.3556 0.3556)
			(layers "F.Cu" "F.Mask" "F.Paste")
			(net "GND")
		)
		(pad "N12" smd circle
			(at -2.800096 -1.999996)
			(size 0.3556 0.3556)
			(layers "F.Cu" "F.Mask" "F.Paste")
			(net "P0V975")
		)
		(pad "N13" smd circle
			(at -1.999996 -1.999996)
			(size 0.3556 0.3556)
			(layers "F.Cu" "F.Mask" "F.Paste")
			(net "GND")
		)
		(pad "N14" smd circle
			(at -1.199896 -1.999996)
			(size 0.3556 0.3556)
			(layers "F.Cu" "F.Mask" "F.Paste")
			(net "P0V975")
		)
		(pad "N15" smd circle
			(at -0.40005 -1.999996)
			(size 0.3556 0.3556)
			(layers "F.Cu" "F.Mask" "F.Paste")
			(net "GND")
		)
		(pad "N16" smd circle
			(at 0.40005 -1.999996)
			(size 0.3556 0.3556)
			(layers "F.Cu" "F.Mask" "F.Paste")
			(net "P0V975")
		)
		(pad "N17" smd circle
			(at 1.199896 -1.999996)
			(size 0.3556 0.3556)
			(layers "F.Cu" "F.Mask" "F.Paste")
			(net "GND")
		)
		(pad "N18" smd circle
			(at 1.999996 -1.999996)
			(size 0.3556 0.3556)
			(layers "F.Cu" "F.Mask" "F.Paste")
			(net "P0V975")
		)
		(pad "N19" smd circle
			(at 2.800096 -1.999996)
			(size 0.3556 0.3556)
			(layers "F.Cu" "F.Mask" "F.Paste")
			(net "GND")
		)
		(pad "N20" smd circle
			(at 3.599942 -1.999996)
			(size 0.3556 0.3556)
			(layers "F.Cu" "F.Mask" "F.Paste")
			(net "P0V975")
		)
		(pad "N21" smd circle
			(at 4.400042 -1.999996)
			(size 0.3556 0.3556)
			(layers "F.Cu" "F.Mask" "F.Paste")
			(net "GND")
		)
		(pad "N22" smd circle
			(at 5.199888 -1.999996)
			(size 0.3556 0.3556)
			(layers "F.Cu" "F.Mask" "F.Paste")
			(net "GND")
		)
		(pad "N23" smd circle
			(at 5.999988 -1.999996)
			(size 0.3556 0.3556)
			(layers "F.Cu" "F.Mask" "F.Paste")
			(net "GND")
		)
		(pad "N24" smd circle
			(at 6.800088 -1.999996)
			(size 0.3556 0.3556)
			(layers "F.Cu" "F.Mask" "F.Paste")
			(net "GND")
		)
		(pad "N25" smd circle
			(at 7.599934 -1.999996)
			(size 0.3556 0.3556)
			(layers "F.Cu" "F.Mask" "F.Paste")
			(net "GND")
		)
		(pad "N26" smd circle
			(at 8.400034 -1.999996)
			(size 0.3556 0.3556)
			(layers "F.Cu" "F.Mask" "F.Paste")
			(net "GND")
		)
		(pad "N27" smd circle
			(at 9.19988 -1.999996)
			(size 0.3556 0.3556)
			(layers "F.Cu" "F.Mask" "F.Paste")
			(net "P1V8_C")
		)
		(pad "N28" smd circle
			(at 9.99998 -1.999996)
			(size 0.3556 0.3556)
			(layers "F.Cu" "F.Mask" "F.Paste")
			(net "IOC_GPIO_32")
		)
		(pad "N29" smd circle
			(at 10.80008 -1.999996)
			(size 0.3556 0.3556)
			(layers "F.Cu" "F.Mask" "F.Paste")
			(net "MEM_CLK_SEL")
		)
		(pad "N30" smd circle
			(at 11.599926 -1.999996)
			(size 0.3556 0.3556)
			(layers "F.Cu" "F.Mask" "F.Paste")
			(net "SBL_SDA")
		)
		(pad "P1" smd circle
			(at -11.599926 -1.199896)
			(size 0.3556 0.3556)
			(layers "F.Cu" "F.Mask" "F.Paste")
			(net "IOC_REF_CLK_P")
		)
		(pad "P2" smd circle
			(at -10.80008 -1.199896)
			(size 0.3556 0.3556)
			(layers "F.Cu" "F.Mask" "F.Paste")
			(net "IOC_REF_CLK_N")
		)
		(pad "P3" smd circle
			(at -9.99998 -1.199896)
			(size 0.3556 0.3556)
			(layers "F.Cu" "F.Mask" "F.Paste")
			(net "GND")
		)
		(pad "P4" smd circle
			(at -9.19988 -1.199896)
			(size 0.3556 0.3556)
			(layers "F.Cu" "F.Mask" "F.Paste")
			(net "P1V8_C")
		)
		(pad "P5" smd circle
			(at -8.400034 -1.199896)
			(size 0.3556 0.3556)
			(layers "F.Cu" "F.Mask" "F.Paste")
			(net "Net_1194")
		)
		(pad "P6" smd circle
			(at -7.599934 -1.199896)
			(size 0.3556 0.3556)
			(layers "F.Cu" "F.Mask" "F.Paste")
			(net "Net_1195")
		)
		(pad "P7" smd circle
			(at -6.800088 -1.199896)
			(size 0.3556 0.3556)
			(layers "F.Cu" "F.Mask" "F.Paste")
			(net "GND")
		)
		(pad "P8" smd circle
			(at -5.999988 -1.199896)
			(size 0.3556 0.3556)
			(layers "F.Cu" "F.Mask" "F.Paste")
			(net "GND")
		)
		(pad "P9" smd circle
			(at -5.199888 -1.199896)
			(size 0.3556 0.3556)
			(layers "F.Cu" "F.Mask" "F.Paste")
			(net "GND")
		)
		(pad "P10" smd circle
			(at -4.400042 -1.199896)
			(size 0.3556 0.3556)
			(layers "F.Cu" "F.Mask" "F.Paste")
			(net "GND")
		)
		(pad "P11" smd circle
			(at -3.599942 -1.199896)
			(size 0.3556 0.3556)
			(layers "F.Cu" "F.Mask" "F.Paste")
			(net "GND")
		)
		(pad "P12" smd circle
			(at -2.800096 -1.199896)
			(size 0.3556 0.3556)
			(layers "F.Cu" "F.Mask" "F.Paste")
			(net "GND")
		)
		(pad "P13" smd circle
			(at -1.999996 -1.199896)
			(size 0.3556 0.3556)
			(layers "F.Cu" "F.Mask" "F.Paste")
			(net "P0V975")
		)
		(pad "P14" smd circle
			(at -1.199896 -1.199896)
			(size 0.3556 0.3556)
			(layers "F.Cu" "F.Mask" "F.Paste")
			(net "GND")
		)
		(pad "P15" smd circle
			(at -0.40005 -1.199896)
			(size 0.3556 0.3556)
			(layers "F.Cu" "F.Mask" "F.Paste")
			(net "P0V975")
		)
		(pad "P16" smd circle
			(at 0.40005 -1.199896)
			(size 0.3556 0.3556)
			(layers "F.Cu" "F.Mask" "F.Paste")
			(net "GND")
		)
		(pad "P17" smd circle
			(at 1.199896 -1.199896)
			(size 0.3556 0.3556)
			(layers "F.Cu" "F.Mask" "F.Paste")
			(net "P0V975")
		)
		(pad "P18" smd circle
			(at 1.999996 -1.199896)
			(size 0.3556 0.3556)
			(layers "F.Cu" "F.Mask" "F.Paste")
			(net "GND")
		)
		(pad "P19" smd circle
			(at 2.800096 -1.199896)
			(size 0.3556 0.3556)
			(layers "F.Cu" "F.Mask" "F.Paste")
			(net "P0V975")
		)
		(pad "P20" smd circle
			(at 3.599942 -1.199896)
			(size 0.3556 0.3556)
			(layers "F.Cu" "F.Mask" "F.Paste")
			(net "GND")
		)
		(pad "P21" smd circle
			(at 4.400042 -1.199896)
			(size 0.3556 0.3556)
			(layers "F.Cu" "F.Mask" "F.Paste")
			(net "P0V975")
		)
		(pad "P22" smd circle
			(at 5.199888 -1.199896)
			(size 0.3556 0.3556)
			(layers "F.Cu" "F.Mask" "F.Paste")
			(net "GND")
		)
		(pad "P23" smd circle
			(at 5.999988 -1.199896)
			(size 0.3556 0.3556)
			(layers "F.Cu" "F.Mask" "F.Paste")
			(net "GND")
		)
		(pad "P24" smd circle
			(at 6.800088 -1.199896)
			(size 0.3556 0.3556)
			(layers "F.Cu" "F.Mask" "F.Paste")
			(net "GND")
		)
		(pad "P25" smd circle
			(at 7.599934 -1.199896)
			(size 0.3556 0.3556)
			(layers "F.Cu" "F.Mask" "F.Paste")
			(net "GND")
		)
		(pad "P26" smd circle
			(at 8.400034 -1.199896)
			(size 0.3556 0.3556)
			(layers "F.Cu" "F.Mask" "F.Paste")
			(net "P1V8_C")
		)
		(pad "P27" smd circle
			(at 9.19988 -1.199896)
			(size 0.3556 0.3556)
			(layers "F.Cu" "F.Mask" "F.Paste")
			(net "GND")
		)
		(pad "P28" smd circle
			(at 9.99998 -1.199896)
			(size 0.3556 0.3556)
			(layers "F.Cu" "F.Mask" "F.Paste")
			(net "I2C_IOC_3_SCL")
		)
		(pad "P29" smd circle
			(at 10.80008 -1.199896)
			(size 0.3556 0.3556)
			(layers "F.Cu" "F.Mask" "F.Paste")
			(net "IOC_CLK_SEL0")
		)
		(pad "P30" smd circle
			(at 11.599926 -1.199896)
			(size 0.3556 0.3556)
			(layers "F.Cu" "F.Mask" "F.Paste")
			(net "I2C_IOC_1_SCL")
		)
		(pad "R1" smd circle
			(at -11.599926 -0.40005)
			(size 0.3556 0.3556)
			(layers "F.Cu" "F.Mask" "F.Paste")
			(net "GND")
		)
		(pad "R2" smd circle
			(at -10.80008 -0.40005)
			(size 0.3556 0.3556)
			(layers "F.Cu" "F.Mask" "F.Paste")
			(net "GND")
		)
		(pad "R3" smd circle
			(at -9.99998 -0.40005)
			(size 0.3556 0.3556)
			(layers "F.Cu" "F.Mask" "F.Paste")
			(net "GND")
		)
		(pad "R4" smd circle
			(at -9.19988 -0.40005)
			(size 0.3556 0.3556)
			(layers "F.Cu" "F.Mask" "F.Paste")
			(net "GND")
		)
		(pad "R5" smd circle
			(at -8.400034 -0.40005)
			(size 0.3556 0.3556)
			(layers "F.Cu" "F.Mask" "F.Paste")
			(net "IOC_SIO_BLINK")
		)
		(pad "R6" smd circle
			(at -7.599934 -0.40005)
			(size 0.3556 0.3556)
			(layers "F.Cu" "F.Mask" "F.Paste")
			(net "POWERLOSS#")
		)
		(pad "R7" smd circle
			(at -6.800088 -0.40005)
			(size 0.3556 0.3556)
			(layers "F.Cu" "F.Mask" "F.Paste")
			(net "GND")
		)
		(pad "R8" smd circle
			(at -5.999988 -0.40005)
			(size 0.3556 0.3556)
			(layers "F.Cu" "F.Mask" "F.Paste")
			(net "GND")
		)
		(pad "R9" smd circle
			(at -5.199888 -0.40005)
			(size 0.3556 0.3556)
			(layers "F.Cu" "F.Mask" "F.Paste")
			(net "GND")
		)
		(pad "R10" smd circle
			(at -4.400042 -0.40005)
			(size 0.3556 0.3556)
			(layers "F.Cu" "F.Mask" "F.Paste")
			(net "GND")
		)
	)
)
